FILE_TYPE=LIBRARY_PARTS;
primitive 'MOSFET_NCH_4D1S';
  pin
    '1':
      PIN_NUMBER='(1)';
      BIDIRECTIONAL='TRUE';
      INPUT_LOAD='(-0.01,0.01)';
      OUTPUT_LOAD='(1.0,-1.0)';
    '6':
      PIN_NUMBER='(6)';
      BIDIRECTIONAL='TRUE';
      INPUT_LOAD='(-0.01,0.01)';
      OUTPUT_LOAD='(1.0,-1.0)';
    '3':
      PIN_NUMBER='(3)';
      INPUT_LOAD='(-0.01,0.01)';
    '2':
      PIN_NUMBER='(2)';
      BIDIRECTIONAL='TRUE';
      INPUT_LOAD='(-0.01,0.01)';
      OUTPUT_LOAD='(1.0,-1.0)';
    '4':
      PIN_NUMBER='(4)';
      BIDIRECTIONAL='TRUE';
      INPUT_LOAD='(-0.01,0.01)';
      OUTPUT_LOAD='(1.0,-1.0)';
    '5':
      PIN_NUMBER='(5)';
      BIDIRECTIONAL='TRUE';
      INPUT_LOAD='(-0.01,0.01)';
      OUTPUT_LOAD='(1.0,-1.0)';
  end_pin;
  body
    PART_NAME='MOSFET_NCH_4D1S';
    BODY_NAME='MOSFET_NCH_4D1S';
    PHYS_DES_PREFIX='Q';
    CLASS='DISCRETE';
  end_body;
end_primitive;

END.
